(kicad_pcb
	(version 20260206)
	(generator "pcbnew")
	(generator_version "10.0")
	(general
		(thickness 1.6)
		(legacy_teardrops no)
	)
	(paper "A4")
	(title_block
		(title "04192023_DAF0TMB3IC0_F0TG_MB_C_brd_V02_OCP.brd")
		(comment 1 "Grand Teton / footprints 7574-7581 of 8354")
	)
	(layers
		(0 "F.Cu" signal "TOP")
		(4 "In1.Cu" signal "GND")
		(6 "In2.Cu" signal "IN1")
		(8 "In3.Cu" signal "GND1")
		(10 "In4.Cu" signal "IN2")
		(12 "In5.Cu" signal "GND2")
		(14 "In6.Cu" signal "IN3")
		(16 "In7.Cu" signal "GND3")
		(18 "In8.Cu" signal "VCC")
		(20 "In9.Cu" signal "VCC1")
		(22 "In10.Cu" signal "GND4")
		(24 "In11.Cu" signal "IN4")
		(26 "In12.Cu" signal "GND5")
		(28 "In13.Cu" signal "IN5")
		(30 "In14.Cu" signal "GND6")
		(32 "In15.Cu" signal "IN6")
		(34 "In16.Cu" signal "GND7")
		(2 "B.Cu" signal "BOTTOM")
		(9 "F.Adhes" user "F.Adhesive")
		(11 "B.Adhes" user "B.Adhesive")
		(13 "F.Paste" user "Package Geometry/Pastemask Top")
		(15 "B.Paste" user "Package Geometry/Pastemask Bottom")
		(5 "F.SilkS" user "Ref Des/Silkscreen Top")
		(7 "B.SilkS" user "Ref Des/Silkscreen Bottom")
		(1 "F.Mask" user "Board Geometry/Soldermask Top")
		(3 "B.Mask" user "Board Geometry/Soldermask Bottom")
		(17 "Dwgs.User" user "User.Drawings")
		(19 "Cmts.User" user "User.Comments")
		(21 "Eco1.User" user "User.Eco1")
		(23 "Eco2.User" user "User.Eco2")
		(25 "Edge.Cuts" user "Board Geometry/Outline")
		(27 "Margin" user)
		(31 "F.CrtYd" user "Package Geometry/Place Bound Top")
		(29 "B.CrtYd" user "Package Geometry/Place Bound Bottom")
		(35 "F.Fab" user "Ref Des/Assembly Top")
		(33 "B.Fab" user "Ref Des/Assembly Bottom")
	)
	(footprint ""
		(layer "B.Cu")
		(at 371.297454 -267.498576)
		(property "Reference" "C2207"
			(at 0 0 0)
			(layer "B.SilkS")
			(hide yes)
			(effects
				(font
					(size 1.27 1.27)
				)
				(justify mirror)
			)
		)
		(property "Value" ""
			(at 0 0 0)
			(layer "B.Fab")
			(effects
				(font
					(size 1.27 1.27)
				)
				(justify mirror)
			)
		)
		(duplicate_pad_numbers_are_jumpers no)
		(fp_line
			(start -0.7874 -0.4064)
			(end -0.7874 0.4064)
			(stroke
				(width 0.1524)
				(type default)
			)
			(layer "B.SilkS")
		)
		(fp_line
			(start -0.7874 0.4064)
			(end 0.7874 0.4064)
			(stroke
				(width 0.1524)
				(type default)
			)
			(layer "B.SilkS")
		)
		(fp_line
			(start 0.7874 -0.4064)
			(end -0.7874 -0.4064)
			(stroke
				(width 0.1524)
				(type default)
			)
			(layer "B.SilkS")
		)
		(fp_line
			(start 0.7874 0.4064)
			(end 0.7874 -0.4064)
			(stroke
				(width 0.1524)
				(type default)
			)
			(layer "B.SilkS")
		)
		(fp_line
			(start -0.67945 -0.3048)
			(end -0.67945 0.3048)
			(stroke
				(width 0.1)
				(type default)
			)
			(layer "B.Fab")
		)
		(fp_line
			(start -0.67945 0.3048)
			(end -0.120396 0.3048)
			(stroke
				(width 0.1)
				(type default)
			)
			(layer "B.Fab")
		)
		(fp_line
			(start -0.12065 -0.3048)
			(end -0.67945 -0.3048)
			(stroke
				(width 0.1)
				(type default)
			)
			(layer "B.Fab")
		)
		(fp_line
			(start -0.12065 -0.2794)
			(end -0.12065 -0.3048)
			(stroke
				(width 0.1)
				(type default)
			)
			(layer "B.Fab")
		)
		(fp_line
			(start -0.120396 0.2794)
			(end 0.12065 0.2794)
			(stroke
				(width 0.1)
				(type default)
			)
			(layer "B.Fab")
		)
		(fp_line
			(start -0.120396 0.3048)
			(end -0.120396 0.2794)
			(stroke
				(width 0.1)
				(type default)
			)
			(layer "B.Fab")
		)
		(fp_line
			(start 0.12065 -0.305054)
			(end 0.12065 -0.2794)
			(stroke
				(width 0.1)
				(type default)
			)
			(layer "B.Fab")
		)
		(fp_line
			(start 0.12065 -0.2794)
			(end -0.12065 -0.2794)
			(stroke
				(width 0.1)
				(type default)
			)
			(layer "B.Fab")
		)
		(fp_line
			(start 0.12065 0.2794)
			(end 0.12065 0.3048)
			(stroke
				(width 0.1)
				(type default)
			)
			(layer "B.Fab")
		)
		(fp_line
			(start 0.12065 0.3048)
			(end 0.67945 0.3048)
			(stroke
				(width 0.1)
				(type default)
			)
			(layer "B.Fab")
		)
		(fp_line
			(start 0.67945 -0.305054)
			(end 0.12065 -0.305054)
			(stroke
				(width 0.1)
				(type default)
			)
			(layer "B.Fab")
		)
		(fp_line
			(start 0.67945 0.3048)
			(end 0.67945 -0.305054)
			(stroke
				(width 0.1)
				(type default)
			)
			(layer "B.Fab")
		)
		(pad "1" smd circle
			(at 0.40005 0 180)
			(size 0 0)
			(layers "B.Cu" "B.Mask" "B.Paste")
			(net "PVDDCR_CPU1_P0")
		)
		(pad "2" smd circle
			(at -0.40005 0 180)
			(size 0 0)
			(layers "B.Cu" "B.Mask" "B.Paste")
			(net "GND")
		)
	)
	(footprint ""
		(layer "B.Cu")
		(at 415.146236 -396.393162 -90)
		(property "Reference" "C785"
			(at 0 0 90)
			(layer "B.SilkS")
			(hide yes)
			(effects
				(font
					(size 1.27 1.27)
				)
				(justify mirror)
			)
		)
		(property "Value" ""
			(at 0 0 90)
			(layer "B.Fab")
			(effects
				(font
					(size 1.27 1.27)
				)
				(justify mirror)
			)
		)
		(duplicate_pad_numbers_are_jumpers no)
		(fp_line
			(start -0.299974 0.150114)
			(end 0.299974 0.150114)
			(stroke
				(width 0.1)
				(type default)
			)
			(layer "B.Fab")
		)
		(fp_line
			(start 0.299974 0.150114)
			(end 0.299974 -0.150114)
			(stroke
				(width 0.1)
				(type default)
			)
			(layer "B.Fab")
		)
		(fp_line
			(start -0.299974 -0.150114)
			(end -0.299974 0.150114)
			(stroke
				(width 0.1)
				(type default)
			)
			(layer "B.Fab")
		)
		(fp_line
			(start 0.299974 -0.150114)
			(end -0.299974 -0.150114)
			(stroke
				(width 0.1)
				(type default)
			)
			(layer "B.Fab")
		)
		(pad "1" smd rect
			(at 0.2667 0 90)
			(size 0.3048 0.381)
			(layers "B.Cu" "B.Mask" "B.Paste")
			(net "P0V9_CPU0_RT_2D")
		)
		(pad "2" smd rect
			(at -0.2667 0 90)
			(size 0.3048 0.381)
			(layers "B.Cu" "B.Mask" "B.Paste")
			(net "GND")
		)
	)
	(footprint ""
		(layer "B.Cu")
		(at 314.318142 -396.393162 -90)
		(property "Reference" "C516"
			(at 0 0 90)
			(layer "B.SilkS")
			(hide yes)
			(effects
				(font
					(size 1.27 1.27)
				)
				(justify mirror)
			)
		)
		(property "Value" ""
			(at 0 0 90)
			(layer "B.Fab")
			(effects
				(font
					(size 1.27 1.27)
				)
				(justify mirror)
			)
		)
		(duplicate_pad_numbers_are_jumpers no)
		(fp_line
			(start -0.299974 0.150114)
			(end 0.299974 0.150114)
			(stroke
				(width 0.1)
				(type default)
			)
			(layer "B.Fab")
		)
		(fp_line
			(start 0.299974 0.150114)
			(end 0.299974 -0.150114)
			(stroke
				(width 0.1)
				(type default)
			)
			(layer "B.Fab")
		)
		(fp_line
			(start -0.299974 -0.150114)
			(end -0.299974 0.150114)
			(stroke
				(width 0.1)
				(type default)
			)
			(layer "B.Fab")
		)
		(fp_line
			(start 0.299974 -0.150114)
			(end -0.299974 -0.150114)
			(stroke
				(width 0.1)
				(type default)
			)
			(layer "B.Fab")
		)
		(pad "1" smd rect
			(at 0.2667 0 90)
			(size 0.3048 0.381)
			(layers "B.Cu" "B.Mask" "B.Paste")
			(net "P1V8_CPU0_RT0_1A_1D")
		)
		(pad "2" smd rect
			(at -0.2667 0 90)
			(size 0.3048 0.381)
			(layers "B.Cu" "B.Mask" "B.Paste")
			(net "GND")
		)
	)
	(footprint ""
		(layer "B.Cu")
		(at 111.800386 -251.400564 180)
		(property "Reference" "C2277"
			(at 0 0 0)
			(layer "B.SilkS")
			(hide yes)
			(effects
				(font
					(size 1.27 1.27)
				)
				(justify mirror)
			)
		)
		(property "Value" ""
			(at 0 0 0)
			(layer "B.Fab")
			(effects
				(font
					(size 1.27 1.27)
				)
				(justify mirror)
			)
		)
		(duplicate_pad_numbers_are_jumpers no)
		(fp_line
			(start 0.7874 0.4064)
			(end 0.7874 -0.4064)
			(stroke
				(width 0.1524)
				(type default)
			)
			(layer "B.SilkS")
		)
		(fp_line
			(start 0.7874 -0.4064)
			(end -0.7874 -0.4064)
			(stroke
				(width 0.1524)
				(type default)
			)
			(layer "B.SilkS")
		)
		(fp_line
			(start -0.7874 0.4064)
			(end 0.7874 0.4064)
			(stroke
				(width 0.1524)
				(type default)
			)
			(layer "B.SilkS")
		)
		(fp_line
			(start -0.7874 -0.4064)
			(end -0.7874 0.4064)
			(stroke
				(width 0.1524)
				(type default)
			)
			(layer "B.SilkS")
		)
		(fp_line
			(start 0.67945 0.3048)
			(end 0.67945 -0.305054)
			(stroke
				(width 0.1)
				(type default)
			)
			(layer "B.Fab")
		)
		(fp_line
			(start 0.67945 -0.305054)
			(end 0.12065 -0.305054)
			(stroke
				(width 0.1)
				(type default)
			)
			(layer "B.Fab")
		)
		(fp_line
			(start 0.12065 0.3048)
			(end 0.67945 0.3048)
			(stroke
				(width 0.1)
				(type default)
			)
			(layer "B.Fab")
		)
		(fp_line
			(start 0.12065 0.2794)
			(end 0.12065 0.3048)
			(stroke
				(width 0.1)
				(type default)
			)
			(layer "B.Fab")
		)
		(fp_line
			(start 0.12065 -0.2794)
			(end -0.12065 -0.2794)
			(stroke
				(width 0.1)
				(type default)
			)
			(layer "B.Fab")
		)
		(fp_line
			(start 0.12065 -0.305054)
			(end 0.12065 -0.2794)
			(stroke
				(width 0.1)
				(type default)
			)
			(layer "B.Fab")
		)
		(fp_line
			(start -0.120396 0.3048)
			(end -0.120396 0.2794)
			(stroke
				(width 0.1)
				(type default)
			)
			(layer "B.Fab")
		)
		(fp_line
			(start -0.120396 0.2794)
			(end 0.12065 0.2794)
			(stroke
				(width 0.1)
				(type default)
			)
			(layer "B.Fab")
		)
		(fp_line
			(start -0.12065 -0.2794)
			(end -0.12065 -0.3048)
			(stroke
				(width 0.1)
				(type default)
			)
			(layer "B.Fab")
		)
		(fp_line
			(start -0.12065 -0.3048)
			(end -0.67945 -0.3048)
			(stroke
				(width 0.1)
				(type default)
			)
			(layer "B.Fab")
		)
		(fp_line
			(start -0.67945 0.3048)
			(end -0.120396 0.3048)
			(stroke
				(width 0.1)
				(type default)
			)
			(layer "B.Fab")
		)
		(fp_line
			(start -0.67945 -0.3048)
			(end -0.67945 0.3048)
			(stroke
				(width 0.1)
				(type default)
			)
			(layer "B.Fab")
		)
		(pad "1" smd circle
			(at 0.40005 0)
			(size 0 0)
			(layers "B.Cu" "B.Mask" "B.Paste")
			(net "PVDDCR_SOC_P1")
		)
		(pad "2" smd circle
			(at -0.40005 0)
			(size 0 0)
			(layers "B.Cu" "B.Mask" "B.Paste")
			(net "GND")
		)
	)
	(footprint ""
		(layer "B.Cu")
		(at 104.580182 -386.745988 -90)
		(property "Reference" "C127"
			(at 0 0 90)
			(layer "B.SilkS")
			(hide yes)
			(effects
				(font
					(size 1.27 1.27)
				)
				(justify mirror)
			)
		)
		(property "Value" ""
			(at 0 0 90)
			(layer "B.Fab")
			(effects
				(font
					(size 1.27 1.27)
				)
				(justify mirror)
			)
		)
		(duplicate_pad_numbers_are_jumpers no)
		(fp_line
			(start -0.7874 0.4064)
			(end 0.7874 0.4064)
			(stroke
				(width 0.1524)
				(type default)
			)
			(layer "B.SilkS")
		)
		(fp_line
			(start 0.7874 0.4064)
			(end 0.7874 -0.4064)
			(stroke
				(width 0.1524)
				(type default)
			)
			(layer "B.SilkS")
		)
		(fp_line
			(start -0.7874 -0.4064)
			(end -0.7874 0.4064)
			(stroke
				(width 0.1524)
				(type default)
			)
			(layer "B.SilkS")
		)
		(fp_line
			(start 0.7874 -0.4064)
			(end -0.7874 -0.4064)
			(stroke
				(width 0.1524)
				(type default)
			)
			(layer "B.SilkS")
		)
		(fp_line
			(start -0.67945 0.3048)
			(end -0.120396 0.3048)
			(stroke
				(width 0.1)
				(type default)
			)
			(layer "B.Fab")
		)
		(fp_line
			(start -0.120396 0.3048)
			(end -0.120396 0.2794)
			(stroke
				(width 0.1)
				(type default)
			)
			(layer "B.Fab")
		)
		(fp_line
			(start 0.12065 0.3048)
			(end 0.67945 0.3048)
			(stroke
				(width 0.1)
				(type default)
			)
			(layer "B.Fab")
		)
		(fp_line
			(start 0.67945 0.3048)
			(end 0.67945 -0.305054)
			(stroke
				(width 0.1)
				(type default)
			)
			(layer "B.Fab")
		)
		(fp_line
			(start -0.120396 0.2794)
			(end 0.12065 0.2794)
			(stroke
				(width 0.1)
				(type default)
			)
			(layer "B.Fab")
		)
		(fp_line
			(start 0.12065 0.2794)
			(end 0.12065 0.3048)
			(stroke
				(width 0.1)
				(type default)
			)
			(layer "B.Fab")
		)
		(fp_line
			(start -0.12065 -0.2794)
			(end -0.12065 -0.3048)
			(stroke
				(width 0.1)
				(type default)
			)
			(layer "B.Fab")
		)
		(fp_line
			(start 0.12065 -0.2794)
			(end -0.12065 -0.2794)
			(stroke
				(width 0.1)
				(type default)
			)
			(layer "B.Fab")
		)
		(fp_line
			(start -0.67945 -0.3048)
			(end -0.67945 0.3048)
			(stroke
				(width 0.1)
				(type default)
			)
			(layer "B.Fab")
		)
		(fp_line
			(start -0.12065 -0.3048)
			(end -0.67945 -0.3048)
			(stroke
				(width 0.1)
				(type default)
			)
			(layer "B.Fab")
		)
		(fp_line
			(start 0.12065 -0.305054)
			(end 0.12065 -0.2794)
			(stroke
				(width 0.1)
				(type default)
			)
			(layer "B.Fab")
		)
		(fp_line
			(start 0.67945 -0.305054)
			(end 0.12065 -0.305054)
			(stroke
				(width 0.1)
				(type default)
			)
			(layer "B.Fab")
		)
		(pad "1" smd circle
			(at 0.40005 0 90)
			(size 0 0)
			(layers "B.Cu" "B.Mask" "B.Paste")
			(net "P1V8_CPU1_RT_1D")
		)
		(pad "2" smd circle
			(at -0.40005 0 90)
			(size 0 0)
			(layers "B.Cu" "B.Mask" "B.Paste")
			(net "GND")
		)
	)
	(footprint ""
		(layer "B.Cu")
		(at 393.617958 -325.878952)
		(property "Reference" "R471"
			(at 0 0 0)
			(layer "B.SilkS")
			(hide yes)
			(effects
				(font
					(size 1.27 1.27)
				)
				(justify mirror)
			)
		)
		(property "Value" ""
			(at 0 0 0)
			(layer "B.Fab")
			(effects
				(font
					(size 1.27 1.27)
				)
				(justify mirror)
			)
		)
		(duplicate_pad_numbers_are_jumpers no)
		(fp_line
			(start -0.7874 -0.4064)
			(end -0.7874 0.4064)
			(stroke
				(width 0.1524)
				(type default)
			)
			(layer "B.SilkS")
		)
		(fp_line
			(start -0.7874 0.4064)
			(end 0.7874 0.4064)
			(stroke
				(width 0.1524)
				(type default)
			)
			(layer "B.SilkS")
		)
		(fp_line
			(start 0.7874 -0.4064)
			(end -0.7874 -0.4064)
			(stroke
				(width 0.1524)
				(type default)
			)
			(layer "B.SilkS")
		)
		(fp_line
			(start 0.7874 0.4064)
			(end 0.7874 -0.4064)
			(stroke
				(width 0.1524)
				(type default)
			)
			(layer "B.SilkS")
		)
		(fp_line
			(start -0.67945 -0.3048)
			(end -0.67945 0.3048)
			(stroke
				(width 0.1)
				(type default)
			)
			(layer "B.Fab")
		)
		(fp_line
			(start -0.67945 0.3048)
			(end -0.120396 0.3048)
			(stroke
				(width 0.1)
				(type default)
			)
			(layer "B.Fab")
		)
		(fp_line
			(start -0.12065 -0.3048)
			(end -0.67945 -0.3048)
			(stroke
				(width 0.1)
				(type default)
			)
			(layer "B.Fab")
		)
		(fp_line
			(start -0.12065 -0.2794)
			(end -0.12065 -0.3048)
			(stroke
				(width 0.1)
				(type default)
			)
			(layer "B.Fab")
		)
		(fp_line
			(start -0.120396 0.2794)
			(end 0.12065 0.2794)
			(stroke
				(width 0.1)
				(type default)
			)
			(layer "B.Fab")
		)
		(fp_line
			(start -0.120396 0.3048)
			(end -0.120396 0.2794)
			(stroke
				(width 0.1)
				(type default)
			)
			(layer "B.Fab")
		)
		(fp_line
			(start 0.12065 -0.305054)
			(end 0.12065 -0.2794)
			(stroke
				(width 0.1)
				(type default)
			)
			(layer "B.Fab")
		)
		(fp_line
			(start 0.12065 -0.2794)
			(end -0.12065 -0.2794)
			(stroke
				(width 0.1)
				(type default)
			)
			(layer "B.Fab")
		)
		(fp_line
			(start 0.12065 0.2794)
			(end 0.12065 0.3048)
			(stroke
				(width 0.1)
				(type default)
			)
			(layer "B.Fab")
		)
		(fp_line
			(start 0.12065 0.3048)
			(end 0.67945 0.3048)
			(stroke
				(width 0.1)
				(type default)
			)
			(layer "B.Fab")
		)
		(fp_line
			(start 0.67945 -0.305054)
			(end 0.12065 -0.305054)
			(stroke
				(width 0.1)
				(type default)
			)
			(layer "B.Fab")
		)
		(fp_line
			(start 0.67945 0.3048)
			(end 0.67945 -0.305054)
			(stroke
				(width 0.1)
				(type default)
			)
			(layer "B.Fab")
		)
		(pad "1" smd circle
			(at 0.40005 0 180)
			(size 0 0)
			(layers "B.Cu" "B.Mask" "B.Paste")
			(net "ESPI_CPU0_D3")
		)
		(pad "2" smd circle
			(at -0.40005 0 180)
			(size 0 0)
			(layers "B.Cu" "B.Mask" "B.Paste")
			(net "ESPI_CPU0_R_D3")
		)
	)
	(footprint ""
		(layer "B.Cu")
		(at 283.980636 -193.99631)
		(property "Reference" "C100"
			(at 0 0 0)
			(layer "B.SilkS")
			(hide yes)
			(effects
				(font
					(size 1.27 1.27)
				)
				(justify mirror)
			)
		)
		(property "Value" ""
			(at 0 0 0)
			(layer "B.Fab")
			(effects
				(font
					(size 1.27 1.27)
				)
				(justify mirror)
			)
		)
		(duplicate_pad_numbers_are_jumpers no)
		(fp_line
			(start -0.7874 -0.4064)
			(end -0.7874 0.4064)
			(stroke
				(width 0.1524)
				(type default)
			)
			(layer "B.SilkS")
		)
		(fp_line
			(start -0.7874 0.4064)
			(end 0.7874 0.4064)
			(stroke
				(width 0.1524)
				(type default)
			)
			(layer "B.SilkS")
		)
		(fp_line
			(start 0.7874 -0.4064)
			(end -0.7874 -0.4064)
			(stroke
				(width 0.1524)
				(type default)
			)
			(layer "B.SilkS")
		)
		(fp_line
			(start 0.7874 0.4064)
			(end 0.7874 -0.4064)
			(stroke
				(width 0.1524)
				(type default)
			)
			(layer "B.SilkS")
		)
		(fp_line
			(start -0.67945 -0.3048)
			(end -0.67945 0.3048)
			(stroke
				(width 0.1)
				(type default)
			)
			(layer "B.Fab")
		)
		(fp_line
			(start -0.67945 0.3048)
			(end -0.120396 0.3048)
			(stroke
				(width 0.1)
				(type default)
			)
			(layer "B.Fab")
		)
		(fp_line
			(start -0.12065 -0.3048)
			(end -0.67945 -0.3048)
			(stroke
				(width 0.1)
				(type default)
			)
			(layer "B.Fab")
		)
		(fp_line
			(start -0.12065 -0.2794)
			(end -0.12065 -0.3048)
			(stroke
				(width 0.1)
				(type default)
			)
			(layer "B.Fab")
		)
		(fp_line
			(start -0.120396 0.2794)
			(end 0.12065 0.2794)
			(stroke
				(width 0.1)
				(type default)
			)
			(layer "B.Fab")
		)
		(fp_line
			(start -0.120396 0.3048)
			(end -0.120396 0.2794)
			(stroke
				(width 0.1)
				(type default)
			)
			(layer "B.Fab")
		)
		(fp_line
			(start 0.12065 -0.305054)
			(end 0.12065 -0.2794)
			(stroke
				(width 0.1)
				(type default)
			)
			(layer "B.Fab")
		)
		(fp_line
			(start 0.12065 -0.2794)
			(end -0.12065 -0.2794)
			(stroke
				(width 0.1)
				(type default)
			)
			(layer "B.Fab")
		)
		(fp_line
			(start 0.12065 0.2794)
			(end 0.12065 0.3048)
			(stroke
				(width 0.1)
				(type default)
			)
			(layer "B.Fab")
		)
		(fp_line
			(start 0.12065 0.3048)
			(end 0.67945 0.3048)
			(stroke
				(width 0.1)
				(type default)
			)
			(layer "B.Fab")
		)
		(fp_line
			(start 0.67945 -0.305054)
			(end 0.12065 -0.305054)
			(stroke
				(width 0.1)
				(type default)
			)
			(layer "B.Fab")
		)
		(fp_line
			(start 0.67945 0.3048)
			(end 0.67945 -0.305054)
			(stroke
				(width 0.1)
				(type default)
			)
			(layer "B.Fab")
		)
		(pad "1" smd circle
			(at 0.40005 0 180)
			(size 0 0)
			(layers "B.Cu" "B.Mask" "B.Paste")
			(net "P3V3_AUX")
		)
		(pad "2" smd circle
			(at -0.40005 0 180)
			(size 0 0)
			(layers "B.Cu" "B.Mask" "B.Paste")
			(net "GND")
		)
	)
	(footprint ""
		(layer "B.Cu")
		(at 238.633 -339.598 180)
		(property "Reference" "R807"
			(at 0 0 0)
			(layer "B.SilkS")
			(hide yes)
			(effects
				(font
					(size 1.27 1.27)
				)
				(justify mirror)
			)
		)
		(property "Value" ""
			(at 0 0 0)
			(layer "B.Fab")
			(effects
				(font
					(size 1.27 1.27)
				)
				(justify mirror)
			)
		)
		(duplicate_pad_numbers_are_jumpers no)
		(fp_line
			(start 0.32512 0.175006)
			(end 0.32512 -0.175006)
			(stroke
				(width 0.1)
				(type default)
			)
			(layer "B.Fab")
		)
		(fp_line
			(start 0.32512 -0.175006)
			(end -0.32512 -0.175006)
			(stroke
				(width 0.1)
				(type default)
			)
			(layer "B.Fab")
		)
		(fp_line
			(start -0.32512 0.175006)
			(end 0.32512 0.175006)
			(stroke
				(width 0.1)
				(type default)
			)
			(layer "B.Fab")
		)
		(fp_line
			(start -0.32512 -0.175006)
			(end -0.32512 0.175006)
			(stroke
				(width 0.1)
				(type default)
			)
			(layer "B.Fab")
		)
		(pad "1" smd rect
			(at 0.2667 0)
			(size 0.3048 0.381)
			(layers "B.Cu" "B.Mask" "B.Paste")
			(net "SMB_RT_CPU1_P3_ROM_MUX_2D_SCL")
		)
		(pad "2" smd rect
			(at -0.2667 0 180)
			(size 0.3048 0.381)
			(layers "B.Cu" "B.Mask" "B.Paste")
			(net "SMB_RT_CPU1_P3_ROM_MUX_2D_R_SCL")
		)
	)
)
